FILE_TYPE = MULTI_PHYS_TABLE;

PART '74CBTLV3126PW'

{========================================================================================}
:VALUE           | PART_TYPE | MATERIAL | PART_NUMBER    = STANDARD    | LIFECYCLE     | PART_NUMBER   | JEDEC_TYPE | DESCRIPTION                          | MANUFTR | MANUF_PN        | RD_CMPLS_LVL | CMPLS_LVL | FROM_PJ       | CLASS | DIP_SMD | DATA                  | EE_CHECK_LIST | FP_ECN | PSL | CREATOR | STATUS | CREATEDAY  ;
{========================================================================================}
 '74CBTLV3126PW' | 'SMLF'    | 'IC'     | 'AL003126K08'(!) = ''               | ''               | 'AL003126K08' |'TSSOP14'| 'IC OTHER(14P) 74CBTLV3126PW(TSSOP)' | 'NXP'   | '74CBTLV3126PW' | 'EU(V1)'     | ''        | 'S4L-CHARLES' | 'IC'  | ''      | 'NXP_74CBTLV3126.pdf' | ''            | ''     | ''  | ''      | ''     | '20130102'
 '74CBTLV3126PW' | 'SMLF'    | 'EMPTY'  | 'AL003126K08'(!) = ''               | ''               | 'AL003126K08' |'TSSOP14'| 'IC OTHER(14P) 74CBTLV3126PW(TSSOP)' | 'NXP'   | '74CBTLV3126PW' | 'EU(V1)'     | ''        | 'S4L-CHARLES' | 'IC'  | ''      | 'NXP_74CBTLV3126.pdf' | ''            | ''     | ''  | ''      | ''     | '20130102'

END_PART

END.

